# S9S_MB_2U (Grand Teton) — schematic netlist excerpt (pin names and nets, part order shuffled) for the footprints in the layout excerpt that follows; sources: Cadence DE-HDL packaged netlist, KiCad conversion of 03242023_DA0F0TMBIJ0_F0T_Motherboard_J_brd_V01_OCP.brd

J65  PICOPROBE_BXA  DELTA-L 4.0 EMPTY  pkg TRIANG_LAUNCH_3PXB  page 308
  \1_p\  = DELTA_L_85_5INCH_IN1_DP
  \2_n\  = DELTA_L_85_5INCH_IN1_DN
  \3_g\  = DELTA_L_GND_1

PC416  Q_CAPP  560UF 2.5V 20% OSCON  pkg THLF  page 289 : A = PVCCFA_EHV_FIVRA_CPU1 ; B = GND

(kicad_pcb
	(version 20260206)
	(generator "pcbnew")
	(generator_version "10.0")
	(general
		(thickness 1.6)
		(legacy_teardrops no)
	)
	(paper "A4")
	(title_block
		(title "03242023_DA0F0TMBIJ0_F0T_Motherboard_J_brd_V01_OCP.brd")
		(comment 1 "Grand Teton / footprints 1193-1194 of 6105")
	)
	(layers
		(0 "F.Cu" signal "TOP")
		(4 "In1.Cu" signal "GND")
		(6 "In2.Cu" signal "IN1")
		(8 "In3.Cu" signal "GND1")
		(10 "In4.Cu" signal "IN2")
		(12 "In5.Cu" signal "GND2")
		(14 "In6.Cu" signal "IN3")
		(16 "In7.Cu" signal "GND3")
		(18 "In8.Cu" signal "VCC")
		(20 "In9.Cu" signal "VCC1")
		(22 "In10.Cu" signal "GND4")
		(24 "In11.Cu" signal "IN4")
		(26 "In12.Cu" signal "GND5")
		(28 "In13.Cu" signal "IN5")
		(30 "In14.Cu" signal "GND6")
		(32 "In15.Cu" signal "IN6")
		(34 "In16.Cu" signal "GND7")
		(2 "B.Cu" signal "BOTTOM")
		(9 "F.Adhes" user "F.Adhesive")
		(11 "B.Adhes" user "B.Adhesive")
		(13 "F.Paste" user "Package Geometry/Pastemask Top")
		(15 "B.Paste" user "Package Geometry/Pastemask Bottom")
		(5 "F.SilkS" user "Ref Des/Silkscreen Top")
		(7 "B.SilkS" user "Ref Des/Silkscreen Bottom")
		(1 "F.Mask" user "Board Geometry/Soldermask Top")
		(3 "B.Mask" user "Board Geometry/Soldermask Bottom")
		(17 "Dwgs.User" user "User.Drawings")
		(19 "Cmts.User" user "User.Comments")
		(21 "Eco1.User" user "User.Eco1")
		(23 "Eco2.User" user "User.Eco2")
		(25 "Edge.Cuts" user "Board Geometry/Outline")
		(27 "Margin" user)
		(31 "F.CrtYd" user "Package Geometry/Place Bound Top")
		(29 "B.CrtYd" user "Package Geometry/Place Bound Bottom")
		(35 "F.Fab" user "Ref Des/Assembly Top")
		(33 "B.Fab" user "Ref Des/Assembly Bottom")
	)
	(footprint ""
		(layer "F.Cu")
		(at 52.894738 -337.477608)
		(property "Reference" "PC416"
			(at 0 0 0)
			(layer "F.SilkS")
			(hide yes)
			(effects
				(font
					(size 1.27 1.27)
				)
			)
		)
		(property "Value" ""
			(at 0 0 0)
			(layer "F.Fab")
			(effects
				(font
					(size 1.27 1.27)
				)
			)
		)
		(duplicate_pad_numbers_are_jumpers no)
		(fp_line
			(start 2.750058 0.999998)
			(end -2.750058 0.999998)
			(stroke
				(width 0.1524)
				(type default)
			)
			(layer "F.SilkS")
		)
		(fp_circle
			(center 0 0.999998)
			(end 2.750058 0.999998)
			(stroke
				(width 0.1524)
				(type default)
			)
			(fill no)
			(layer "F.SilkS")
		)
		(fp_poly
			(pts
				(arc
					(start 2.750058 0.999998)
					(mid 0 3.750056)
					(end -2.750058 0.999998)
				)
			)
			(stroke
				(width 0)
				(type default)
			)
			(fill yes)
			(layer "F.SilkS")
		)
		(fp_circle
			(center 0 0.999998)
			(end 2.750058 0.999998)
			(stroke
				(width 0.1)
				(type default)
			)
			(fill no)
			(layer "F.Fab")
		)
		(pad "1" thru_hole rect
			(at 0 0)
			(size 1.5748 1.5748)
			(drill 1.0668)
			(layers "*.Cu" "*.Mask")
			(remove_unused_layers no)
			(net "PVCCFA_EHV_FIVRA_CPU1")
			(clearance 0)
			(padstack
				(mode front_inner_back)
				(layer "Inner"
					(shape circle)
					(size 1.5748 1.5748)
					(clearance 0)
				)
				(layer "B.Cu"
					(shape rect)
					(size 1.5748 1.5748)
					(clearance 0)
				)
			)
		)
		(pad "2" thru_hole circle
			(at 0 1.999996)
			(size 1.5748 1.5748)
			(drill 1.0668)
			(layers "*.Cu" "*.Mask")
			(remove_unused_layers no)
			(net "GND")
			(clearance 0)
		)
	)
	(footprint ""
		(layer "F.Cu")
		(at 378.099574 0.383794 180)
		(property "Reference" "J65"
			(at -4.451096 -1.394206 90)
			(unlocked yes)
			(layer "F.SilkS")
			(effects
				(font
					(size 0.7874 0.5842)
					(thickness 0.1524)
				)
				(justify left)
			)
		)
		(property "Value" ""
			(at 0 0 180)
			(layer "F.Fab")
			(effects
				(font
					(size 1.27 1.27)
				)
			)
		)
		(duplicate_pad_numbers_are_jumpers no)
		(fp_line
			(start 1.2192 2.1082)
			(end -1.2192 2.1082)
			(stroke
				(width 0.1524)
				(type default)
			)
			(layer "F.SilkS")
		)
		(fp_line
			(start 1.2192 -2.1082)
			(end 1.2192 2.1082)
			(stroke
				(width 0.1524)
				(type default)
			)
			(layer "F.SilkS")
		)
		(fp_line
			(start -1.2192 2.1082)
			(end -1.2192 -2.1082)
			(stroke
				(width 0.1524)
				(type default)
			)
			(layer "F.SilkS")
		)
		(fp_line
			(start -1.2192 -2.1082)
			(end 1.2192 -2.1082)
			(stroke
				(width 0.1524)
				(type default)
			)
			(layer "F.SilkS")
		)
		(pad "" np_thru_hole circle
			(at -2.8829 -1.27 90)
			(size 1.0414 1.0414)
			(drill 1.0414)
			(layers "*.Cu" "*.Mask")
			(clearance 0.381)
			(thermal_gap 0.381)
		)
		(pad "" np_thru_hole circle
			(at -2.8829 1.27 90)
			(size 1.0414 1.0414)
			(drill 1.0414)
			(layers "*.Cu" "*.Mask")
			(clearance 0.381)
			(thermal_gap 0.381)
		)
		(pad "" np_thru_hole circle
			(at 3.4671 -1.27 90)
			(size 1.0414 1.0414)
			(drill 1.0414)
			(layers "*.Cu" "*.Mask")
			(clearance 0.381)
			(thermal_gap 0.381)
		)
		(pad "" np_thru_hole circle
			(at 3.4671 1.27 90)
			(size 1.0414 1.0414)
			(drill 1.0414)
			(layers "*.Cu" "*.Mask")
			(clearance 0.381)
			(thermal_gap 0.381)
		)
		(pad "1" smd rect
			(at 0.8255 -0.249936 90)
			(size 0.3048 0.508)
			(layers "F.Cu" "F.Mask" "F.Paste")
			(net "DELTA_L_85_5INCH_IN1_DP")
		)
		(pad "2" smd rect
			(at 0.8255 0.249936 90)
			(size 0.3048 0.508)
			(layers "F.Cu" "F.Mask" "F.Paste")
			(net "DELTA_L_85_5INCH_IN1_DN")
		)
		(pad "3" smd circle
			(at 0 0 180)
			(size 0 0)
			(layers "F.Cu" "F.Mask" "F.Paste")
			(net "DELTA_L_GND_1")
		)
		(zone
			(layer "F.Cu")
			(hatch none 0.5)
			(connect_pads
				(clearance 0)
			)
			(min_thickness 0.25)
			(keepout
				(tracks not_allowed)
				(vias allowed)
				(pads allowed)
				(copperpour not_allowed)
				(footprints allowed)
			)
			(placement
				(enabled no)
				(sheetname "")
			)
			(fill
				(thermal_gap 0.5)
				(thermal_bridge_width 0.5)
				(island_removal_mode 0)
			)
			(polygon
				(pts
					(xy 376.981974 0.932434) (xy 376.981974 0.83693) (xy 377.578874 0.83693) (xy 377.578874 0.43053)
					(xy 376.981974 0.43053) (xy 376.981974 0.337058) (xy 377.578874 0.337058) (xy 377.578874 -0.069342)
					(xy 376.981974 -0.069342) (xy 376.981974 -0.164846) (xy 377.680474 -0.164846) (xy 377.680474 0.932434)
				)
			)
		)
		(zone
			(layers "F.Cu" "B.Cu" "In1.Cu" "In2.Cu" "In3.Cu" "In4.Cu" "In5.Cu" "In6.Cu"
				"In7.Cu" "In8.Cu" "In9.Cu" "In10.Cu" "In11.Cu" "In12.Cu" "In13.Cu" "In14.Cu"
				"In15.Cu" "In16.Cu"
			)
			(hatch none 0.5)
			(connect_pads
				(clearance 0)
			)
			(min_thickness 0.25)
			(keepout
				(tracks not_allowed)
				(vias allowed)
				(pads allowed)
				(copperpour not_allowed)
				(footprints allowed)
			)
			(placement
				(enabled no)
				(sheetname "")
			)
			(fill
				(thermal_gap 0.5)
				(thermal_bridge_width 0.5)
				(island_removal_mode 0)
			)
			(polygon
				(pts
					(arc
						(start 375.559574 -0.886206)
						(mid 373.705374 -0.886206)
						(end 375.559574 -0.886206)
					)
				)
			)
		)
		(zone
			(layers "F.Cu" "B.Cu" "In1.Cu" "In2.Cu" "In3.Cu" "In4.Cu" "In5.Cu" "In6.Cu"
				"In7.Cu" "In8.Cu" "In9.Cu" "In10.Cu" "In11.Cu" "In12.Cu" "In13.Cu" "In14.Cu"
				"In15.Cu" "In16.Cu"
			)
			(hatch none 0.5)
			(connect_pads
				(clearance 0)
			)
			(min_thickness 0.25)
			(keepout
				(tracks not_allowed)
				(vias allowed)
				(pads allowed)
				(copperpour not_allowed)
				(footprints allowed)
			)
			(placement
				(enabled no)
				(sheetname "")
			)
			(fill
				(thermal_gap 0.5)
				(thermal_bridge_width 0.5)
				(island_removal_mode 0)
			)
			(polygon
				(pts
					(arc
						(start 375.559574 1.653794)
						(mid 373.705374 1.653794)
						(end 375.559574 1.653794)
					)
				)
			)
		)
		(zone
			(layers "F.Cu" "B.Cu" "In1.Cu" "In2.Cu" "In3.Cu" "In4.Cu" "In5.Cu" "In6.Cu"
				"In7.Cu" "In8.Cu" "In9.Cu" "In10.Cu" "In11.Cu" "In12.Cu" "In13.Cu" "In14.Cu"
				"In15.Cu" "In16.Cu"
			)
			(hatch none 0.5)
			(connect_pads
				(clearance 0)
			)
			(min_thickness 0.25)
			(keepout
				(tracks not_allowed)
				(vias allowed)
				(pads allowed)
				(copperpour not_allowed)
				(footprints allowed)
			)
			(placement
				(enabled no)
				(sheetname "")
			)
			(fill
				(thermal_gap 0.5)
				(thermal_bridge_width 0.5)
				(island_removal_mode 0)
			)
			(polygon
				(pts
					(arc
						(start 381.909574 -0.886206)
						(mid 380.055374 -0.886206)
						(end 381.909574 -0.886206)
					)
				)
			)
		)
		(zone
			(layers "F.Cu" "B.Cu" "In1.Cu" "In2.Cu" "In3.Cu" "In4.Cu" "In5.Cu" "In6.Cu"
				"In7.Cu" "In8.Cu" "In9.Cu" "In10.Cu" "In11.Cu" "In12.Cu" "In13.Cu" "In14.Cu"
				"In15.Cu" "In16.Cu"
			)
			(hatch none 0.5)
			(connect_pads
				(clearance 0)
			)
			(min_thickness 0.25)
			(keepout
				(tracks not_allowed)
				(vias allowed)
				(pads allowed)
				(copperpour not_allowed)
				(footprints allowed)
			)
			(placement
				(enabled no)
				(sheetname "")
			)
			(fill
				(thermal_gap 0.5)
				(thermal_bridge_width 0.5)
				(island_removal_mode 0)
			)
			(polygon
				(pts
					(arc
						(start 381.909574 1.653794)
						(mid 380.055374 1.653794)
						(end 381.909574 1.653794)
					)
				)
			)
		)
	)
)
